# T6G (Grand Teton) — schematic netlist excerpt (pin names and nets, part order shuffled) for the footprints in the layout excerpt that follows; sources: Cadence DE-HDL packaged netlist, KiCad conversion of 04192023_DAF0TMB3IC0_F0TG_MB_C_brd_V02_OCP.brd

R724  Q_RES  4.7K 5% EMPTY  pkg 0201LF  page 320 : A = P1V8_CPU1_RT_1D ; B = TEST2_RT_CPU1_P0

H114  GND_HOLE  EMPTY  pkg TH  page 230
  GND2  = GND
  GND3  = GND
  GND4  = GND
  GND5  = GND
  GND6  = GND
  GND7  = GND
  GND8  = GND
  GND9  = GND

(kicad_pcb
	(version 20260206)
	(generator "pcbnew")
	(generator_version "10.0")
	(general
		(thickness 1.6)
		(legacy_teardrops no)
	)
	(paper "A4")
	(title_block
		(title "04192023_DAF0TMB3IC0_F0TG_MB_C_brd_V02_OCP.brd")
		(comment 1 "Grand Teton / footprints 418-419 of 8354")
	)
	(layers
		(0 "F.Cu" signal "TOP")
		(4 "In1.Cu" signal "GND")
		(6 "In2.Cu" signal "IN1")
		(8 "In3.Cu" signal "GND1")
		(10 "In4.Cu" signal "IN2")
		(12 "In5.Cu" signal "GND2")
		(14 "In6.Cu" signal "IN3")
		(16 "In7.Cu" signal "GND3")
		(18 "In8.Cu" signal "VCC")
		(20 "In9.Cu" signal "VCC1")
		(22 "In10.Cu" signal "GND4")
		(24 "In11.Cu" signal "IN4")
		(26 "In12.Cu" signal "GND5")
		(28 "In13.Cu" signal "IN5")
		(30 "In14.Cu" signal "GND6")
		(32 "In15.Cu" signal "IN6")
		(34 "In16.Cu" signal "GND7")
		(2 "B.Cu" signal "BOTTOM")
		(9 "F.Adhes" user "F.Adhesive")
		(11 "B.Adhes" user "B.Adhesive")
		(13 "F.Paste" user "Package Geometry/Pastemask Top")
		(15 "B.Paste" user "Package Geometry/Pastemask Bottom")
		(5 "F.SilkS" user "Ref Des/Silkscreen Top")
		(7 "B.SilkS" user "Ref Des/Silkscreen Bottom")
		(1 "F.Mask" user "Board Geometry/Soldermask Top")
		(3 "B.Mask" user "Board Geometry/Soldermask Bottom")
		(17 "Dwgs.User" user "User.Drawings")
		(19 "Cmts.User" user "User.Comments")
		(21 "Eco1.User" user "User.Eco1")
		(23 "Eco2.User" user "User.Eco2")
		(25 "Edge.Cuts" user "Board Geometry/Outline")
		(27 "Margin" user)
		(31 "F.CrtYd" user "Package Geometry/Place Bound Top")
		(29 "B.CrtYd" user "Package Geometry/Place Bound Bottom")
		(35 "F.Fab" user "Ref Des/Assembly Top")
		(33 "B.Fab" user "Ref Des/Assembly Bottom")
	)
	(footprint ""
		(layer "F.Cu")
		(at 268.645386 -51.999896)
		(property "Reference" "H114"
			(at -8.10006 -6.85419 0)
			(unlocked yes)
			(layer "F.SilkS")
			(effects
				(font
					(size 0.7874 0.5842)
					(thickness 0.1524)
				)
				(justify left)
			)
		)
		(property "Value" ""
			(at 0 0 0)
			(layer "F.Fab")
			(effects
				(font
					(size 1.27 1.27)
				)
			)
		)
		(duplicate_pad_numbers_are_jumpers no)
		(fp_circle
			(center 0 0)
			(end 7.999984 0)
			(stroke
				(width 0.1524)
				(type default)
			)
			(fill no)
			(layer "F.SilkS")
		)
		(fp_circle
			(center 0 0)
			(end 7.999984 0)
			(stroke
				(width 0.1524)
				(type default)
			)
			(fill no)
			(layer "B.SilkS")
		)
		(fp_circle
			(center 0 0)
			(end 7.999984 0)
			(stroke
				(width 0.1)
				(type default)
			)
			(fill no)
			(layer "B.Fab")
		)
		(fp_circle
			(center 0 0)
			(end 7.999984 0)
			(stroke
				(width 0.1)
				(type default)
			)
			(fill no)
			(layer "F.Fab")
		)
		(pad "" np_thru_hole circle
			(at 0 0)
			(size 5.5118 5.5118)
			(drill 5.5118)
			(layers "*.Cu" "*.Mask")
			(clearance 0.381)
			(thermal_gap 0.381)
		)
		(pad "2" thru_hole circle
			(at 0 -3.999992)
			(size 0.762 0.762)
			(drill 0.5588)
			(layers "*.Cu" "*.Mask")
			(remove_unused_layers no)
			(net "GND")
			(clearance 0.1524)
			(thermal_gap 0.1524)
		)
		(pad "3" thru_hole circle
			(at -2.999994 -2.500122)
			(size 0.762 0.762)
			(drill 0.5588)
			(layers "*.Cu" "*.Mask")
			(remove_unused_layers no)
			(net "GND")
			(clearance 0.1524)
			(thermal_gap 0.1524)
		)
		(pad "4" thru_hole circle
			(at -3.999992 0)
			(size 0.762 0.762)
			(drill 0.5588)
			(layers "*.Cu" "*.Mask")
			(remove_unused_layers no)
			(net "GND")
			(clearance 0.1524)
			(thermal_gap 0.1524)
		)
		(pad "5" thru_hole circle
			(at -2.999994 2.500122)
			(size 0.762 0.762)
			(drill 0.5588)
			(layers "*.Cu" "*.Mask")
			(remove_unused_layers no)
			(net "GND")
			(clearance 0.1524)
			(thermal_gap 0.1524)
		)
		(pad "6" thru_hole circle
			(at 0 3.999992)
			(size 0.762 0.762)
			(drill 0.5588)
			(layers "*.Cu" "*.Mask")
			(remove_unused_layers no)
			(net "GND")
			(clearance 0.1524)
			(thermal_gap 0.1524)
		)
		(pad "7" thru_hole circle
			(at 2.999994 2.500122)
			(size 0.762 0.762)
			(drill 0.5588)
			(layers "*.Cu" "*.Mask")
			(remove_unused_layers no)
			(net "GND")
			(clearance 0.1524)
			(thermal_gap 0.1524)
		)
		(pad "8" thru_hole circle
			(at 3.999992 0)
			(size 0.762 0.762)
			(drill 0.5588)
			(layers "*.Cu" "*.Mask")
			(remove_unused_layers no)
			(net "GND")
			(clearance 0.1524)
			(thermal_gap 0.1524)
		)
		(pad "9" thru_hole circle
			(at 2.999994 -2.500122)
			(size 0.762 0.762)
			(drill 0.5588)
			(layers "*.Cu" "*.Mask")
			(remove_unused_layers no)
			(net "GND")
			(clearance 0.1524)
			(thermal_gap 0.1524)
		)
		(zone
			(layer "F.Cu")
			(hatch none 0.5)
			(connect_pads
				(clearance 0)
			)
			(min_thickness 0.25)
			(keepout
				(tracks not_allowed)
				(vias allowed)
				(pads allowed)
				(copperpour not_allowed)
				(footprints allowed)
			)
			(placement
				(enabled no)
				(sheetname "")
			)
			(fill
				(thermal_gap 0.5)
				(thermal_bridge_width 0.5)
				(island_removal_mode 0)
			)
			(polygon
				(pts
					(arc
						(start 268.645386 -59.99988)
						(mid 262.988543 -57.656739)
						(end 260.645402 -51.999896)
					)
					(arc
						(start 260.645402 -51.999896)
						(mid 262.988543 -46.343053)
						(end 268.645386 -43.999912)
					)
					(xy 268.645386 -46.74616) (xy 268.594332 -46.74616)
					(arc
						(start 268.594078 -46.74616)
						(mid 263.391399 -51.999896)
						(end 268.594078 -57.253632)
					)
					(xy 268.594332 -57.253632) (xy 268.645386 -57.253632)
				)
			)
		)
		(zone
			(layer "F.Cu")
			(hatch none 0.5)
			(connect_pads
				(clearance 0)
			)
			(min_thickness 0.25)
			(keepout
				(tracks not_allowed)
				(vias allowed)
				(pads allowed)
				(copperpour not_allowed)
				(footprints allowed)
			)
			(placement
				(enabled no)
				(sheetname "")
			)
			(fill
				(thermal_gap 0.5)
				(thermal_bridge_width 0.5)
				(island_removal_mode 0)
			)
			(polygon
				(pts
					(arc
						(start 268.645386 -59.99988)
						(mid 274.302229 -57.656739)
						(end 276.64537 -51.999896)
					)
					(arc
						(start 276.64537 -51.999896)
						(mid 274.302229 -46.343053)
						(end 268.645386 -43.999912)
					)
					(xy 268.645386 -46.74616) (xy 268.69644 -46.74616)
					(arc
						(start 268.696694 -46.74616)
						(mid 273.899373 -51.999896)
						(end 268.696694 -57.253632)
					)
					(xy 268.69644 -57.253632) (xy 268.645386 -57.253632)
				)
			)
		)
		(zone
			(layers "F.Cu" "B.Cu" "In1.Cu" "In2.Cu" "In3.Cu" "In4.Cu" "In5.Cu" "In6.Cu"
				"In7.Cu" "In8.Cu" "In9.Cu" "In10.Cu" "In11.Cu" "In12.Cu" "In13.Cu" "In14.Cu"
				"In15.Cu" "In16.Cu"
			)
			(hatch none 0.5)
			(connect_pads
				(clearance 0)
			)
			(min_thickness 0.25)
			(keepout
				(tracks not_allowed)
				(vias allowed)
				(pads allowed)
				(copperpour not_allowed)
				(footprints allowed)
			)
			(placement
				(enabled no)
				(sheetname "")
			)
			(fill
				(thermal_gap 0.5)
				(thermal_bridge_width 0.5)
				(island_removal_mode 0)
			)
			(polygon
				(pts
					(arc
						(start 271.921986 -51.999896)
						(mid 265.368786 -51.999896)
						(end 271.921986 -51.999896)
					)
				)
			)
		)
		(zone
			(layer "B.Cu")
			(hatch none 0.5)
			(connect_pads
				(clearance 0)
			)
			(min_thickness 0.25)
			(keepout
				(tracks not_allowed)
				(vias allowed)
				(pads allowed)
				(copperpour not_allowed)
				(footprints allowed)
			)
			(placement
				(enabled no)
				(sheetname "")
			)
			(fill
				(thermal_gap 0.5)
				(thermal_bridge_width 0.5)
				(island_removal_mode 0)
			)
			(polygon
				(pts
					(arc
						(start 268.645386 -57.507886)
						(mid 263.137396 -51.999896)
						(end 268.645386 -46.491906)
					)
					(arc
						(start 268.645386 -46.974506)
						(mid 263.619996 -51.999896)
						(end 268.645386 -57.025286)
					)
				)
			)
		)
		(zone
			(layer "B.Cu")
			(hatch none 0.5)
			(connect_pads
				(clearance 0)
			)
			(min_thickness 0.25)
			(keepout
				(tracks not_allowed)
				(vias allowed)
				(pads allowed)
				(copperpour not_allowed)
				(footprints allowed)
			)
			(placement
				(enabled no)
				(sheetname "")
			)
			(fill
				(thermal_gap 0.5)
				(thermal_bridge_width 0.5)
				(island_removal_mode 0)
			)
			(polygon
				(pts
					(arc
						(start 268.645386 -57.507886)
						(mid 274.153376 -51.999896)
						(end 268.645386 -46.491906)
					)
					(arc
						(start 268.645386 -46.974506)
						(mid 273.670776 -51.999896)
						(end 268.645386 -57.025286)
					)
				)
			)
		)
	)
	(footprint ""
		(layer "F.Cu")
		(at 41.741852 -383.7432)
		(property "Reference" "R724"
			(at 0 0 0)
			(layer "F.SilkS")
			(hide yes)
			(effects
				(font
					(size 1.27 1.27)
				)
			)
		)
		(property "Value" ""
			(at 0 0 0)
			(layer "F.Fab")
			(effects
				(font
					(size 1.27 1.27)
				)
			)
		)
		(duplicate_pad_numbers_are_jumpers no)
		(fp_line
			(start -0.32512 -0.175006)
			(end 0.32512 -0.175006)
			(stroke
				(width 0.1)
				(type default)
			)
			(layer "F.Fab")
		)
		(fp_line
			(start -0.32512 0.175006)
			(end -0.32512 -0.175006)
			(stroke
				(width 0.1)
				(type default)
			)
			(layer "F.Fab")
		)
		(fp_line
			(start 0.32512 -0.175006)
			(end 0.32512 0.175006)
			(stroke
				(width 0.1)
				(type default)
			)
			(layer "F.Fab")
		)
		(fp_line
			(start 0.32512 0.175006)
			(end -0.32512 0.175006)
			(stroke
				(width 0.1)
				(type default)
			)
			(layer "F.Fab")
		)
		(pad "1" smd rect
			(at -0.2667 0)
			(size 0.3048 0.381)
			(layers "F.Cu" "F.Mask" "F.Paste")
			(net "P1V8_CPU1_RT_1D")
		)
		(pad "2" smd rect
			(at 0.2667 0 180)
			(size 0.3048 0.381)
			(layers "F.Cu" "F.Mask" "F.Paste")
			(net "TEST2_RT_CPU1_P0")
		)
	)
)
